(kicad_pcb
	(version 20260206)
	(generator "pcbnew")
	(generator_version "10.0")
	(general
		(thickness 1.6)
		(legacy_teardrops no)
	)
	(paper "A4")
	(title_block
		(title "Wiwynn_Tioga_Pass_MB.brd")
		(comment 1 "Tioga Pass / footprints 1549-1554 of 4770")
	)
	(layers
		(0 "F.Cu" signal "TOP")
		(4 "In1.Cu" signal "L2GND")
		(6 "In2.Cu" signal "L3")
		(8 "In3.Cu" signal "L4GND")
		(10 "In4.Cu" signal "L5")
		(12 "In5.Cu" signal "L6GND")
		(14 "In6.Cu" signal "L7VCC")
		(16 "In7.Cu" signal "L8VCC")
		(18 "In8.Cu" signal "L9GND")
		(20 "In9.Cu" signal "L10")
		(22 "In10.Cu" signal "L11GND")
		(24 "In11.Cu" signal "L12")
		(26 "In12.Cu" signal "L13GND")
		(2 "B.Cu" signal "BOTTOM")
		(9 "F.Adhes" user "F.Adhesive")
		(11 "B.Adhes" user "B.Adhesive")
		(13 "F.Paste" user "Package Geometry/Pastemask Top")
		(15 "B.Paste" user "Package Geometry/Pastemask Bottom")
		(5 "F.SilkS" user "Ref Des/Silkscreen Top")
		(7 "B.SilkS" user "Ref Des/Silkscreen Bottom")
		(1 "F.Mask" user "Board Geometry/Soldermask Top")
		(3 "B.Mask" user "Board Geometry/Soldermask Bottom")
		(17 "Dwgs.User" user "User.Drawings")
		(19 "Cmts.User" user "User.Comments")
		(21 "Eco1.User" user "User.Eco1")
		(23 "Eco2.User" user "User.Eco2")
		(25 "Edge.Cuts" user "Board Geometry/Outline")
		(27 "Margin" user)
		(31 "F.CrtYd" user "Package Geometry/Place Bound Top")
		(29 "B.CrtYd" user "Package Geometry/Place Bound Bottom")
		(35 "F.Fab" user "Ref Des/Assembly Top")
		(33 "B.Fab" user "Ref Des/Assembly Bottom")
	)
	(footprint ""
		(layer "F.Cu")
		(at 13.35024 -165.01618 -90)
		(property "Reference" "T1D1"
			(at 0 0 270)
			(layer "F.SilkS")
			(hide yes)
			(effects
				(font
					(size 1.27 1.27)
				)
			)
		)
		(property "Value" "*"
			(at -3.4036 -4.46405 270)
			(unlocked yes)
			(layer "F.Fab")
			(hide yes)
			(effects
				(font
					(size 0.889 0.889)
					(thickness 0.1524)
				)
			)
		)
		(property "Device Type" "TEST-PAD-12P-1-GP-U_DISCRET-GBA"
			(at -3.4036 -5.98805 270)
			(unlocked yes)
			(layer "F.Fab")
			(hide yes)
			(effects
				(font
					(size 0.889 0.889)
					(thickness 0.1524)
				)
			)
		)
		(duplicate_pad_numbers_are_jumpers no)
		(fp_line
			(start -2.3876 3.4798)
			(end -2.3876 -4.826)
			(stroke
				(width 0.1524)
				(type default)
			)
			(layer "F.SilkS")
		)
		(fp_line
			(start 2.3622 3.4798)
			(end -2.3876 3.4798)
			(stroke
				(width 0.1524)
				(type default)
			)
			(layer "F.SilkS")
		)
		(fp_line
			(start -2.3876 -4.826)
			(end 2.3622 -4.826)
			(stroke
				(width 0.1524)
				(type default)
			)
			(layer "F.SilkS")
		)
		(fp_line
			(start 2.3622 -4.826)
			(end 2.3622 3.4798)
			(stroke
				(width 0.1524)
				(type default)
			)
			(layer "F.SilkS")
		)
		(fp_rect
			(start -2.6416 3.7338)
			(end 2.6162 -5.08)
			(stroke
				(width 0)
				(type default)
			)
			(fill no)
			(layer "F.CrtYd")
		)
		(fp_rect
			(start -2.6416 3.7338)
			(end 2.6162 -5.08)
			(stroke
				(width 0)
				(type default)
			)
			(fill no)
			(layer "F.Fab")
		)
		(pad "1" smd circle
			(at 0.496824 -1.301496 270)
			(size 0.6604 0.6604)
			(layers "F.Cu" "F.Mask" "F.Paste")
			(net "L1_85OHM_5INCH_DP")
		)
		(pad "2" smd circle
			(at -0.503936 -1.301496 270)
			(size 0.6604 0.6604)
			(layers "F.Cu" "F.Mask" "F.Paste")
			(net "L1_85OHM_5INCH_DN")
		)
		(pad "3" smd custom
			(at -0.00889 0.370078 270)
			(size 0.74295 0.74295)
			(layers "F.Cu" "F.Mask" "F.Paste")
			(net "GND")
			(options
				(clearance outline)
				(anchor circle)
			)
			(primitives
				(gr_poly
					(pts
						(xy -2.1209 1.4859) (xy 2.1209 1.4859) (xy 2.1209 -1.4859) (xy 1.08585 -1.4859) (xy 1.08585 -0.4699)
						(xy -1.08585 -0.4699) (xy -1.08585 -1.4859) (xy -2.1209 -1.4859)
					)
					(width 0)
					(fill yes)
				)
			)
		)
		(pad "4" thru_hole circle
			(at 1.266444 -3.851656 270)
			(size 1.4478 1.4478)
			(drill 1.0414)
			(layers "*.Cu" "*.Mask")
			(remove_unused_layers no)
			(net "GND")
			(clearance 0.1524)
			(thermal_gap 0.1524)
		)
		(pad "5" thru_hole circle
			(at -1.273556 -3.851656 270)
			(size 1.4478 1.4478)
			(drill 1.0414)
			(layers "*.Cu" "*.Mask")
			(remove_unused_layers no)
			(net "GND")
			(clearance 0.1524)
			(thermal_gap 0.1524)
		)
		(pad "6" thru_hole circle
			(at 1.266444 2.498344 270)
			(size 1.4478 1.4478)
			(drill 1.0414)
			(layers "*.Cu" "*.Mask")
			(remove_unused_layers no)
			(net "GND")
			(clearance 0.1524)
			(thermal_gap 0.1524)
		)
		(pad "7" thru_hole circle
			(at -1.273556 2.498344 270)
			(size 1.4478 1.4478)
			(drill 1.0414)
			(layers "*.Cu" "*.Mask")
			(remove_unused_layers no)
			(net "GND")
			(clearance 0.1524)
			(thermal_gap 0.1524)
		)
		(pad "8" thru_hole circle
			(at 1.27 -0.4572 270)
			(size 0.7112 0.7112)
			(drill 0.4064)
			(layers "*.Cu" "*.Mask")
			(remove_unused_layers no)
			(net "GND")
			(clearance 0.1016)
			(thermal_gap 0.1016)
		)
		(pad "9" thru_hole circle
			(at 1.27 0.762 270)
			(size 0.7112 0.7112)
			(drill 0.4064)
			(layers "*.Cu" "*.Mask")
			(remove_unused_layers no)
			(net "GND")
			(clearance 0.1016)
			(thermal_gap 0.1016)
		)
		(pad "10" thru_hole circle
			(at -0.0254 0.762 270)
			(size 0.7112 0.7112)
			(drill 0.4064)
			(layers "*.Cu" "*.Mask")
			(remove_unused_layers no)
			(net "GND")
			(clearance 0.1016)
			(thermal_gap 0.1016)
		)
		(pad "11" thru_hole circle
			(at -1.27 0.762 270)
			(size 0.7112 0.7112)
			(drill 0.4064)
			(layers "*.Cu" "*.Mask")
			(remove_unused_layers no)
			(net "GND")
			(clearance 0.1016)
			(thermal_gap 0.1016)
		)
		(pad "12" thru_hole circle
			(at -1.27 -0.4572 270)
			(size 0.7112 0.7112)
			(drill 0.4064)
			(layers "*.Cu" "*.Mask")
			(remove_unused_layers no)
			(net "GND")
			(clearance 0.1016)
			(thermal_gap 0.1016)
		)
	)
	(footprint ""
		(layer "F.Cu")
		(at 204.0509 -52.7304 -90)
		(property "Reference" "CT3"
			(at -0.8382 -0.67818 270)
			(unlocked yes)
			(layer "F.SilkS")
			(effects
				(font
					(size 0.4064 0.254)
					(thickness 0.1524)
				)
				(justify left)
			)
		)
		(property "Value" ""
			(at 0 0 270)
			(layer "F.Fab")
			(effects
				(font
					(size 1.27 1.27)
				)
			)
		)
		(duplicate_pad_numbers_are_jumpers no)
		(fp_poly
			(pts
				(xy 0.3048 -0.1016) (xy 0.3048 0.9906) (xy -0.3048 0.9906) (xy -0.3048 -0.1016)
			)
			(stroke
				(width 0)
				(type default)
			)
			(fill no)
			(layer "F.CrtYd")
		)
		(fp_line
			(start -0.3048 0.9906)
			(end 0.3048 0.9906)
			(stroke
				(width 0.1)
				(type default)
			)
			(layer "F.Fab")
		)
		(fp_line
			(start 0.3048 0.9906)
			(end 0.3048 -0.1016)
			(stroke
				(width 0.1)
				(type default)
			)
			(layer "F.Fab")
		)
		(fp_line
			(start -0.3048 -0.1016)
			(end -0.3048 0.9906)
			(stroke
				(width 0.1)
				(type default)
			)
			(layer "F.Fab")
		)
		(fp_line
			(start 0.3048 -0.1016)
			(end -0.3048 -0.1016)
			(stroke
				(width 0.1)
				(type default)
			)
			(layer "F.Fab")
		)
		(pad "1" smd rect
			(at 0 0 270)
			(size 0.508 0.508)
			(layers "F.Cu" "F.Mask" "F.Paste")
			(net "VR_PVCCIN_CPU0_PHASE1")
		)
		(pad "2" smd rect
			(at 0 0.889 270)
			(size 0.508 0.508)
			(layers "F.Cu" "F.Mask" "F.Paste")
			(net "VR_PVCCIN_CPU0_PHASE1_RC")
		)
		(zone
			(layer "F.Cu")
			(hatch none 0.5)
			(connect_pads
				(clearance 0)
			)
			(min_thickness 0.25)
			(keepout
				(tracks not_allowed)
				(vias allowed)
				(pads allowed)
				(copperpour not_allowed)
				(footprints allowed)
			)
			(placement
				(enabled no)
				(sheetname "")
			)
			(fill
				(thermal_gap 0.5)
				(thermal_bridge_width 0.5)
				(island_removal_mode 0)
			)
			(polygon
				(pts
					(xy 203.4159 -52.9844) (xy 203.4159 -52.4764) (xy 203.7969 -52.4764) (xy 203.7969 -52.9844)
				)
			)
		)
		(zone
			(layer "F.Cu")
			(hatch none 0.5)
			(connect_pads
				(clearance 0)
			)
			(min_thickness 0.25)
			(keepout
				(tracks allowed)
				(vias not_allowed)
				(pads allowed)
				(copperpour not_allowed)
				(footprints allowed)
			)
			(placement
				(enabled no)
				(sheetname "")
			)
			(fill
				(thermal_gap 0.5)
				(thermal_bridge_width 0.5)
				(island_removal_mode 0)
			)
			(polygon
				(pts
					(xy 203.7969 -52.9844) (xy 203.7969 -52.4764) (xy 203.4159 -52.4764) (xy 203.4159 -52.9844)
				)
			)
		)
	)
	(footprint ""
		(layer "F.Cu")
		(at 339.471 -21.971 90)
		(property "Reference" "R7F35"
			(at 0 0 90)
			(layer "F.SilkS")
			(hide yes)
			(effects
				(font
					(size 1.27 1.27)
				)
			)
		)
		(property "Value" ""
			(at 0 0 90)
			(layer "F.Fab")
			(effects
				(font
					(size 1.27 1.27)
				)
			)
		)
		(duplicate_pad_numbers_are_jumpers no)
		(fp_rect
			(start 0.2794 -0.1016)
			(end -0.2794 0.9906)
			(stroke
				(width 0)
				(type default)
			)
			(fill no)
			(layer "F.CrtYd")
		)
		(fp_line
			(start 0.2794 -0.1016)
			(end -0.2794 -0.1016)
			(stroke
				(width 0.1)
				(type default)
			)
			(layer "F.Fab")
		)
		(fp_line
			(start -0.2794 -0.1016)
			(end -0.2794 0.9906)
			(stroke
				(width 0.1)
				(type default)
			)
			(layer "F.Fab")
		)
		(fp_line
			(start 0.2794 0.9906)
			(end 0.2794 -0.1016)
			(stroke
				(width 0.1)
				(type default)
			)
			(layer "F.Fab")
		)
		(fp_line
			(start -0.2794 0.9906)
			(end 0.2794 0.9906)
			(stroke
				(width 0.1)
				(type default)
			)
			(layer "F.Fab")
		)
		(pad "1" smd rect
			(at 0 0 90)
			(size 0.508 0.508)
			(layers "F.Cu" "F.Mask" "F.Paste")
			(net "GND")
		)
		(pad "2" smd rect
			(at 0 0.889 90)
			(size 0.508 0.508)
			(layers "F.Cu" "F.Mask" "F.Paste")
			(net "AGND_PVPP_ABC")
		)
		(zone
			(layer "F.Cu")
			(hatch none 0.5)
			(connect_pads
				(clearance 0)
			)
			(min_thickness 0.25)
			(keepout
				(tracks not_allowed)
				(vias allowed)
				(pads allowed)
				(copperpour not_allowed)
				(footprints allowed)
			)
			(placement
				(enabled no)
				(sheetname "")
			)
			(fill
				(thermal_gap 0.5)
				(thermal_bridge_width 0.5)
				(island_removal_mode 0)
			)
			(polygon
				(pts
					(xy 339.725 -22.225) (xy 339.725 -21.717) (xy 340.106 -21.717) (xy 340.106 -22.225)
				)
			)
		)
		(zone
			(layer "F.Cu")
			(hatch none 0.5)
			(connect_pads
				(clearance 0)
			)
			(min_thickness 0.25)
			(keepout
				(tracks allowed)
				(vias not_allowed)
				(pads allowed)
				(copperpour not_allowed)
				(footprints allowed)
			)
			(placement
				(enabled no)
				(sheetname "")
			)
			(fill
				(thermal_gap 0.5)
				(thermal_bridge_width 0.5)
				(island_removal_mode 0)
			)
			(polygon
				(pts
					(xy 339.725 -22.225) (xy 339.725 -21.717) (xy 340.106 -21.717) (xy 340.106 -22.225)
				)
			)
		)
	)
	(footprint ""
		(layer "F.Cu")
		(at 198.37908 -101.221286 90)
		(property "Reference" "C4C9"
			(at 0 0 90)
			(layer "F.SilkS")
			(hide yes)
			(effects
				(font
					(size 1.27 1.27)
				)
			)
		)
		(property "Value" ""
			(at 0 0 90)
			(layer "F.Fab")
			(effects
				(font
					(size 1.27 1.27)
				)
			)
		)
		(duplicate_pad_numbers_are_jumpers no)
		(fp_poly
			(pts
				(xy 0.3048 -0.1016) (xy 0.3048 0.9906) (xy -0.3048 0.9906) (xy -0.3048 -0.1016)
			)
			(stroke
				(width 0)
				(type default)
			)
			(fill no)
			(layer "F.CrtYd")
		)
		(fp_line
			(start 0.3048 -0.1016)
			(end -0.3048 -0.1016)
			(stroke
				(width 0.1)
				(type default)
			)
			(layer "F.Fab")
		)
		(fp_line
			(start -0.3048 -0.1016)
			(end -0.3048 0.9906)
			(stroke
				(width 0.1)
				(type default)
			)
			(layer "F.Fab")
		)
		(fp_line
			(start 0.3048 0.9906)
			(end 0.3048 -0.1016)
			(stroke
				(width 0.1)
				(type default)
			)
			(layer "F.Fab")
		)
		(fp_line
			(start -0.3048 0.9906)
			(end 0.3048 0.9906)
			(stroke
				(width 0.1)
				(type default)
			)
			(layer "F.Fab")
		)
		(pad "1" smd rect
			(at 0 0 90)
			(size 0.508 0.508)
			(layers "F.Cu" "F.Mask" "F.Paste")
			(net "VR_FET_SW_P12V_STBY_PVCCIN_CPU0")
		)
		(pad "2" smd rect
			(at 0 0.889 90)
			(size 0.508 0.508)
			(layers "F.Cu" "F.Mask" "F.Paste")
			(net "GND")
		)
		(zone
			(layer "F.Cu")
			(hatch none 0.5)
			(connect_pads
				(clearance 0)
			)
			(min_thickness 0.25)
			(keepout
				(tracks allowed)
				(vias not_allowed)
				(pads allowed)
				(copperpour not_allowed)
				(footprints allowed)
			)
			(placement
				(enabled no)
				(sheetname "")
			)
			(fill
				(thermal_gap 0.5)
				(thermal_bridge_width 0.5)
				(island_removal_mode 0)
			)
			(polygon
				(pts
					(xy 198.63308 -100.967286) (xy 198.63308 -101.475286) (xy 199.01408 -101.475286) (xy 199.01408 -100.967286)
				)
			)
		)
		(zone
			(layer "F.Cu")
			(hatch none 0.5)
			(connect_pads
				(clearance 0)
			)
			(min_thickness 0.25)
			(keepout
				(tracks not_allowed)
				(vias allowed)
				(pads allowed)
				(copperpour not_allowed)
				(footprints allowed)
			)
			(placement
				(enabled no)
				(sheetname "")
			)
			(fill
				(thermal_gap 0.5)
				(thermal_bridge_width 0.5)
				(island_removal_mode 0)
			)
			(polygon
				(pts
					(xy 199.01408 -100.967286) (xy 199.01408 -101.475286) (xy 198.63308 -101.475286) (xy 198.63308 -100.967286)
				)
			)
		)
	)
	(footprint ""
		(layer "F.Cu")
		(at 453.8472 -15.3924)
		(property "Reference" "C8F8"
			(at 0 0 0)
			(layer "F.SilkS")
			(hide yes)
			(effects
				(font
					(size 1.27 1.27)
				)
			)
		)
		(property "Value" "*"
			(at 0 -9.7155 0)
			(unlocked yes)
			(layer "F.Fab")
			(hide yes)
			(effects
				(font
					(size 1.27 1.016)
					(thickness 0.1524)
				)
			)
		)
		(property "Device Type" "ST470U6D3VDM-7-GP_SMD-TCG4-ST4A"
			(at 0 -11.2395 0)
			(unlocked yes)
			(layer "F.Fab")
			(hide yes)
			(effects
				(font
					(size 1.27 1.016)
					(thickness 0.1524)
				)
			)
		)
		(duplicate_pad_numbers_are_jumpers no)
		(fp_line
			(start -2.286 -4.8768)
			(end -2.286 -2.032)
			(stroke
				(width 0.1524)
				(type default)
			)
			(layer "F.SilkS")
		)
		(fp_line
			(start -2.286 4.8768)
			(end -2.286 2.032)
			(stroke
				(width 0.1524)
				(type default)
			)
			(layer "F.SilkS")
		)
		(fp_line
			(start 2.1082 -4.699)
			(end -2.1082 -4.699)
			(stroke
				(width 0.508)
				(type default)
			)
			(layer "F.SilkS")
		)
		(fp_line
			(start 2.286 -4.8768)
			(end -2.286 -4.8768)
			(stroke
				(width 0.1524)
				(type default)
			)
			(layer "F.SilkS")
		)
		(fp_line
			(start 2.286 -2.032)
			(end 2.286 -4.8768)
			(stroke
				(width 0.1524)
				(type default)
			)
			(layer "F.SilkS")
		)
		(fp_line
			(start 2.286 2.032)
			(end 2.286 4.8768)
			(stroke
				(width 0.1524)
				(type default)
			)
			(layer "F.SilkS")
		)
		(fp_line
			(start 2.286 4.8768)
			(end -2.286 4.8768)
			(stroke
				(width 0.1524)
				(type default)
			)
			(layer "F.SilkS")
		)
		(fp_rect
			(start -2.1463 3.6449)
			(end 2.1463 -3.6449)
			(stroke
				(width 0)
				(type default)
			)
			(fill no)
			(layer "F.CrtYd")
		)
		(fp_poly
			(pts
				(xy -2.54 4.953) (xy -2.54 4.2926) (xy -3.81 4.2926) (xy -3.81 -4.2926) (xy -2.54 -4.2926) (xy -2.54 -4.953)
				(xy 2.54 -4.953) (xy 2.54 -4.2926) (xy 3.81 -4.2926) (xy 3.81 -1.6256) (xy 2.1463 -1.6256) (xy 2.1463 -3.6449)
				(xy -2.1463 -3.6449) (xy -2.1463 3.6449) (xy 2.1463 3.6449) (xy 2.1463 -1.6129) (xy 3.81 -1.6129)
				(xy 3.81 4.2926) (xy 2.54 4.2926) (xy 2.54 4.953)
			)
			(stroke
				(width 0)
				(type default)
			)
			(fill no)
			(layer "F.CrtYd")
		)
		(fp_rect
			(start -3.81 4.2926)
			(end -2.54 -4.2926)
			(stroke
				(width 0)
				(type default)
			)
			(fill no)
			(layer "F.Fab")
		)
		(fp_rect
			(start -2.54 4.953)
			(end 2.54 -4.953)
			(stroke
				(width 0)
				(type default)
			)
			(fill no)
			(layer "F.Fab")
		)
		(fp_rect
			(start 2.54 4.2926)
			(end 3.81 -4.2926)
			(stroke
				(width 0)
				(type default)
			)
			(fill no)
			(layer "F.Fab")
		)
		(pad "1" smd rect
			(at 0 -3.1496)
			(size 2.413 2.286)
			(layers "F.Cu" "F.Mask" "F.Paste")
			(net "P3V3_STBY")
		)
		(pad "2" smd rect
			(at 0 3.1496)
			(size 2.413 2.286)
			(layers "F.Cu" "F.Mask" "F.Paste")
			(net "GND")
		)
		(zone
			(layer "F.Cu")
			(hatch none 0.5)
			(connect_pads
				(clearance 0)
			)
			(min_thickness 0.25)
			(keepout
				(tracks allowed)
				(vias not_allowed)
				(pads allowed)
				(copperpour not_allowed)
				(footprints allowed)
			)
			(placement
				(enabled no)
				(sheetname "")
			)
			(fill
				(thermal_gap 0.5)
				(thermal_bridge_width 0.5)
				(island_removal_mode 0)
			)
			(polygon
				(pts
					(xy 452.3359 -10.795) (xy 455.3585 -10.795) (xy 455.3585 -13.6906) (xy 455.3585 -14.0208) (xy 452.3359 -14.0208)
					(xy 452.3359 -13.6906)
				)
			)
		)
		(zone
			(layer "F.Cu")
			(hatch none 0.5)
			(connect_pads
				(clearance 0)
			)
			(min_thickness 0.25)
			(keepout
				(tracks allowed)
				(vias not_allowed)
				(pads allowed)
				(copperpour not_allowed)
				(footprints allowed)
			)
			(placement
				(enabled no)
				(sheetname "")
			)
			(fill
				(thermal_gap 0.5)
				(thermal_bridge_width 0.5)
				(island_removal_mode 0)
			)
			(polygon
				(pts
					(xy 455.3585 -17.0815) (xy 455.3585 -19.9898) (xy 452.3359 -19.9898) (xy 452.3359 -17.0942) (xy 452.3359 -16.764)
					(xy 455.3585 -16.764)
				)
			)
		)
	)
	(footprint ""
		(layer "F.Cu")
		(at 351.779332 3.530854 -90)
		(property "Reference" "C7G38"
			(at 0 0 270)
			(layer "F.SilkS")
			(hide yes)
			(effects
				(font
					(size 1.27 1.27)
				)
			)
		)
		(property "Value" ""
			(at 0 0 270)
			(layer "F.Fab")
			(effects
				(font
					(size 1.27 1.27)
				)
			)
		)
		(duplicate_pad_numbers_are_jumpers no)
		(fp_poly
			(pts
				(xy 0.3048 -0.1016) (xy 0.3048 0.9906) (xy -0.3048 0.9906) (xy -0.3048 -0.1016)
			)
			(stroke
				(width 0)
				(type default)
			)
			(fill no)
			(layer "F.CrtYd")
		)
		(fp_line
			(start -0.3048 0.9906)
			(end 0.3048 0.9906)
			(stroke
				(width 0.1)
				(type default)
			)
			(layer "F.Fab")
		)
		(fp_line
			(start 0.3048 0.9906)
			(end 0.3048 -0.1016)
			(stroke
				(width 0.1)
				(type default)
			)
			(layer "F.Fab")
		)
		(fp_line
			(start -0.3048 -0.1016)
			(end -0.3048 0.9906)
			(stroke
				(width 0.1)
				(type default)
			)
			(layer "F.Fab")
		)
		(fp_line
			(start 0.3048 -0.1016)
			(end -0.3048 -0.1016)
			(stroke
				(width 0.1)
				(type default)
			)
			(layer "F.Fab")
		)
		(pad "1" smd rect
			(at 0 0 270)
			(size 0.508 0.508)
			(layers "F.Cu" "F.Mask" "F.Paste")
			(net "VR_PVDDQ_ABC_PH2_BOOT")
		)
		(pad "2" smd rect
			(at 0 0.889 270)
			(size 0.508 0.508)
			(layers "F.Cu" "F.Mask" "F.Paste")
			(net "VR_PVDDQ_ABC_PH2_PHASE")
		)
		(zone
			(layer "F.Cu")
			(hatch none 0.5)
			(connect_pads
				(clearance 0)
			)
			(min_thickness 0.25)
			(keepout
				(tracks not_allowed)
				(vias allowed)
				(pads allowed)
				(copperpour not_allowed)
				(footprints allowed)
			)
			(placement
				(enabled no)
				(sheetname "")
			)
			(fill
				(thermal_gap 0.5)
				(thermal_bridge_width 0.5)
				(island_removal_mode 0)
			)
			(polygon
				(pts
					(xy 351.144332 3.276854) (xy 351.144332 3.784854) (xy 351.525332 3.784854) (xy 351.525332 3.276854)
				)
			)
		)
		(zone
			(layer "F.Cu")
			(hatch none 0.5)
			(connect_pads
				(clearance 0)
			)
			(min_thickness 0.25)
			(keepout
				(tracks allowed)
				(vias not_allowed)
				(pads allowed)
				(copperpour not_allowed)
				(footprints allowed)
			)
			(placement
				(enabled no)
				(sheetname "")
			)
			(fill
				(thermal_gap 0.5)
				(thermal_bridge_width 0.5)
				(island_removal_mode 0)
			)
			(polygon
				(pts
					(xy 351.525332 3.276854) (xy 351.525332 3.784854) (xy 351.144332 3.784854) (xy 351.144332 3.276854)
				)
			)
		)
	)
)
